(kicad_pcb
	(version 20260206)
	(generator "pcbnew")
	(generator_version "10.0")
	(general
		(thickness 1.6)
		(legacy_teardrops no)
	)
	(paper "A4")
	(title_block
		(title "03242023_DA0F0TMBIJ0_F0T_Motherboard_J_brd_V01_OCP.brd")
		(comment 1 "Grand Teton / footprint 1682 of 6105 (U1), pads 1169-1274 of 4677")
	)
	(layers
		(0 "F.Cu" signal "TOP")
		(4 "In1.Cu" signal "GND")
		(6 "In2.Cu" signal "IN1")
		(8 "In3.Cu" signal "GND1")
		(10 "In4.Cu" signal "IN2")
		(12 "In5.Cu" signal "GND2")
		(14 "In6.Cu" signal "IN3")
		(16 "In7.Cu" signal "GND3")
		(18 "In8.Cu" signal "VCC")
		(20 "In9.Cu" signal "VCC1")
		(22 "In10.Cu" signal "GND4")
		(24 "In11.Cu" signal "IN4")
		(26 "In12.Cu" signal "GND5")
		(28 "In13.Cu" signal "IN5")
		(30 "In14.Cu" signal "GND6")
		(32 "In15.Cu" signal "IN6")
		(34 "In16.Cu" signal "GND7")
		(2 "B.Cu" signal "BOTTOM")
		(9 "F.Adhes" user "F.Adhesive")
		(11 "B.Adhes" user "B.Adhesive")
		(13 "F.Paste" user "Package Geometry/Pastemask Top")
		(15 "B.Paste" user "Package Geometry/Pastemask Bottom")
		(5 "F.SilkS" user "Ref Des/Silkscreen Top")
		(7 "B.SilkS" user "Ref Des/Silkscreen Bottom")
		(1 "F.Mask" user "Board Geometry/Soldermask Top")
		(3 "B.Mask" user "Board Geometry/Soldermask Bottom")
		(17 "Dwgs.User" user "User.Drawings")
		(19 "Cmts.User" user "User.Comments")
		(21 "Eco1.User" user "User.Eco1")
		(23 "Eco2.User" user "User.Eco2")
		(25 "Edge.Cuts" user "Board Geometry/Outline")
		(27 "Margin" user)
		(31 "F.CrtYd" user "Package Geometry/Place Bound Top")
		(29 "B.CrtYd" user "Package Geometry/Place Bound Bottom")
		(35 "F.Fab" user "Ref Des/Assembly Top")
		(33 "B.Fab" user "Ref Des/Assembly Bottom")
	)
	(footprint ""
		(layer "F.Cu")
		(at 111.93018 -251.76988 90)
		(property "Reference" "U1"
			(at -74.913236 41.548812 0)
			(unlocked yes)
			(layer "F.SilkS")
			(effects
				(font
					(size 1.6002 1.1938)
					(thickness 0.1524)
				)
				(justify left)
			)
		)
		(property "Value" ""
			(at 0 0 90)
			(layer "F.Fab")
			(effects
				(font
					(size 1.27 1.27)
				)
			)
		)
		(duplicate_pad_numbers_are_jumpers no)
		(pad "BJ5" smd circle
			(at -34.169604 -4.518914 270)
			(size 0.4318 0.4318)
			(layers "F.Cu" "F.Mask" "F.Paste")
			(net "UPI_CPU0_CPU1_P1P0_DN<19>")
		)
		(pad "BJ7" smd circle
			(at -32.541718 -4.518914 270)
			(size 0.4318 0.4318)
			(layers "F.Cu" "F.Mask" "F.Paste")
			(net "PVCCD_HV_CPU1")
		)
		(pad "BJ9" smd circle
			(at -30.914086 -4.518914 270)
			(size 0.4318 0.4318)
			(layers "F.Cu" "F.Mask" "F.Paste")
			(net "P5E_CPU1_PE1_RX_DP<12>")
		)
		(pad "BJ11" smd circle
			(at -29.2862 -4.518914 270)
			(size 0.4318 0.4318)
			(layers "F.Cu" "F.Mask" "F.Paste")
			(net "PVCCD_HV_CPU1")
		)
		(pad "BJ13" smd circle
			(at -27.658314 -4.518914 270)
			(size 0.4318 0.4318)
			(layers "F.Cu" "F.Mask" "F.Paste")
			(net "P5E_CPU1_PE1_TX_DN<13>")
		)
		(pad "BJ15" smd circle
			(at -26.030682 -4.518914 270)
			(size 0.4318 0.4318)
			(layers "F.Cu" "F.Mask" "F.Paste")
			(net "PVCCINFAON_CPU1")
		)
		(pad "BJ17" smd circle
			(at -24.402796 -4.518914 270)
			(size 0.4318 0.4318)
			(layers "F.Cu" "F.Mask" "F.Paste")
			(net "TP_DMI_CPU1_PCH_RX_C_DN<3>")
		)
		(pad "BJ19" smd circle
			(at -22.77491 -4.518914 270)
			(size 0.4318 0.4318)
			(layers "F.Cu" "F.Mask" "F.Paste")
			(net "PVNN_MAIN_CPU1")
		)
		(pad "BJ21" smd circle
			(at -21.147278 -4.518914 270)
			(size 0.4318 0.4318)
			(layers "F.Cu" "F.Mask" "F.Paste")
			(net "NC_CPU1_MDFI_DIE00_NS1")
		)
		(pad "BJ23" smd circle
			(at -19.519392 -4.518914 270)
			(size 0.4318 0.4318)
			(layers "F.Cu" "F.Mask" "F.Paste")
			(net "DBP_CPU1_HOOK8_MBP2_GTL_QS_R_N")
		)
		(pad "BJ25" smd circle
			(at -17.89176 -4.518914 270)
			(size 0.4318 0.4318)
			(layers "F.Cu" "F.Mask" "F.Paste")
			(net "SVID_ALERT1_CPU1_N")
		)
		(pad "BJ60" smd circle
			(at 12.19454 -4.408932 270)
			(size 0.4318 0.4318)
			(layers "F.Cu" "F.Mask" "F.Paste")
			(net "PVCCINFAON_CPU1")
		)
		(pad "BJ62" smd circle
			(at 13.822426 -4.408932 270)
			(size 0.4318 0.4318)
			(layers "F.Cu" "F.Mask" "F.Paste")
			(net "GND")
		)
		(pad "BJ64" smd circle
			(at 15.450058 -4.408932 270)
			(size 0.4318 0.4318)
			(layers "F.Cu" "F.Mask" "F.Paste")
			(net "NC_ESPI_IBL_CPU1_IO1")
		)
		(pad "BJ66" smd circle
			(at 17.07769 -4.408932 270)
			(size 0.4318 0.4318)
			(layers "F.Cu" "F.Mask" "F.Paste")
			(net "TP_TRC_CPU1_PTI<28>")
		)
		(pad "BJ68" smd circle
			(at 18.705576 -4.408932 270)
			(size 0.4318 0.4318)
			(layers "F.Cu" "F.Mask" "F.Paste")
			(net "GND")
		)
		(pad "BJ70" smd circle
			(at 20.333462 -4.408932 270)
			(size 0.4318 0.4318)
			(layers "F.Cu" "F.Mask" "F.Paste")
			(net "CPU1_RSVD<54>")
		)
		(pad "BJ72" smd circle
			(at 21.961094 -4.408932 270)
			(size 0.4318 0.4318)
			(layers "F.Cu" "F.Mask" "F.Paste")
			(net "PVCCFA_EHV_FIVRA_CPU1")
		)
		(pad "BJ74" smd circle
			(at 23.58898 -4.408932 270)
			(size 0.4318 0.4318)
			(layers "F.Cu" "F.Mask" "F.Paste")
			(net "UPI_CPU0_CPU1_P2P2_DP<20>")
		)
		(pad "BJ76" smd circle
			(at 25.216612 -4.408932 270)
			(size 0.4318 0.4318)
			(layers "F.Cu" "F.Mask" "F.Paste")
			(net "UPI_CPU0_CPU1_P2P2_DN<18>")
		)
		(pad "BJ78" smd circle
			(at 26.844498 -4.408932 270)
			(size 0.4318 0.4318)
			(layers "F.Cu" "F.Mask" "F.Paste")
			(net "PVCCFA_EHV_FIVRA_CPU1")
		)
		(pad "BJ80" smd circle
			(at 28.472384 -4.408932 270)
			(size 0.4318 0.4318)
			(layers "F.Cu" "F.Mask" "F.Paste")
			(net "GND")
		)
		(pad "BJ82" smd circle
			(at 30.100016 -4.408932 270)
			(size 0.4318 0.4318)
			(layers "F.Cu" "F.Mask" "F.Paste")
			(net "GND")
		)
		(pad "BJ84" smd circle
			(at 31.727902 -4.408932 270)
			(size 0.4318 0.4318)
			(layers "F.Cu" "F.Mask" "F.Paste")
			(net "GND")
		)
		(pad "BJ86" smd circle
			(at 33.355534 -4.408932 270)
			(size 0.4318 0.4318)
			(layers "F.Cu" "F.Mask" "F.Paste")
			(net "GND")
		)
		(pad "BJ88" smd circle
			(at 34.98342 -4.408932 270)
			(size 0.4318 0.4318)
			(layers "F.Cu" "F.Mask" "F.Paste")
			(net "GND")
		)
		(pad "BJ90" smd circle
			(at 36.611306 -4.408932 270)
			(size 0.4318 0.4318)
			(layers "F.Cu" "F.Mask" "F.Paste")
			(net "GND")
		)
		(pad "BK2" smd circle
			(at -36.611306 -4.049268 270)
			(size 0.4318 0.4318)
			(layers "F.Cu" "F.Mask" "F.Paste")
			(net "UPI_CPU1_CPU0_P0P1_DN<20>")
		)
		(pad "BK4" smd circle
			(at -34.98342 -4.049268 270)
			(size 0.4318 0.4318)
			(layers "F.Cu" "F.Mask" "F.Paste")
			(net "GND")
		)
		(pad "BK6" smd circle
			(at -33.355534 -4.049268 270)
			(size 0.4318 0.4318)
			(layers "F.Cu" "F.Mask" "F.Paste")
			(net "UPI_CPU0_CPU1_P1P0_DN<20>")
		)
		(pad "BK8" smd circle
			(at -31.727902 -4.049268 270)
			(size 0.4318 0.4318)
			(layers "F.Cu" "F.Mask" "F.Paste")
			(net "GND")
		)
		(pad "BK10" smd circle
			(at -30.100016 -4.049268 270)
			(size 0.4318 0.4318)
			(layers "F.Cu" "F.Mask" "F.Paste")
			(net "P5E_CPU1_PE1_RX_DN<12>")
		)
		(pad "BK12" smd circle
			(at -28.472384 -4.049268 270)
			(size 0.4318 0.4318)
			(layers "F.Cu" "F.Mask" "F.Paste")
			(net "GND")
		)
		(pad "BK14" smd circle
			(at -26.844498 -4.049268 270)
			(size 0.4318 0.4318)
			(layers "F.Cu" "F.Mask" "F.Paste")
			(net "P5E_CPU1_PE1_TX_DN<12>")
		)
		(pad "BK16" smd circle
			(at -25.216612 -4.049268 270)
			(size 0.4318 0.4318)
			(layers "F.Cu" "F.Mask" "F.Paste")
			(net "GND")
		)
		(pad "BK18" smd circle
			(at -23.58898 -4.049268 270)
			(size 0.4318 0.4318)
			(layers "F.Cu" "F.Mask" "F.Paste")
			(net "TP_DMI_CPU1_PCH_RX_C_DN<4>")
		)
		(pad "BK20" smd circle
			(at -21.961094 -4.049268 270)
			(size 0.4318 0.4318)
			(layers "F.Cu" "F.Mask" "F.Paste")
			(net "GND")
		)
		(pad "BK22" smd circle
			(at -20.333462 -4.049268 270)
			(size 0.4318 0.4318)
			(layers "F.Cu" "F.Mask" "F.Paste")
			(net "NC_CPU1_MDFI_DIE00_NS0")
		)
		(pad "BK24" smd circle
			(at -18.705576 -4.049268 270)
			(size 0.4318 0.4318)
			(layers "F.Cu" "F.Mask" "F.Paste")
			(net "DBP_CPU1_HOOK9_MBP3_GTL_QS_R_N")
		)
		(pad "BK26" smd circle
			(at -17.07769 -4.049268 270)
			(size 0.4318 0.4318)
			(layers "F.Cu" "F.Mask" "F.Paste")
			(net "SVID_ALERT0_CPU1_N")
		)
		(pad "BK61" smd circle
			(at 13.008356 -3.939286 270)
			(size 0.4318 0.4318)
			(layers "F.Cu" "F.Mask" "F.Paste")
			(net "PVCCINFAON_CPU1")
		)
		(pad "BK63" smd circle
			(at 14.635988 -3.939286 270)
			(size 0.4318 0.4318)
			(layers "F.Cu" "F.Mask" "F.Paste")
			(net "NC_ESPI_IBL_CPU1_IO0")
		)
		(pad "BK65" smd circle
			(at 16.263874 -3.939286 270)
			(size 0.4318 0.4318)
			(layers "F.Cu" "F.Mask" "F.Paste")
			(net "GND")
		)
		(pad "BK67" smd circle
			(at 17.89176 -3.939286 270)
			(size 0.4318 0.4318)
			(layers "F.Cu" "F.Mask" "F.Paste")
			(net "TP_TRC_CPU1_PTI3_CLK")
		)
		(pad "BK69" smd circle
			(at 19.519392 -3.939286 270)
			(size 0.4318 0.4318)
			(layers "F.Cu" "F.Mask" "F.Paste")
			(net "TP_TRC_CPU1_PTI<24>")
		)
		(pad "BK71" smd circle
			(at 21.147278 -3.939286 270)
			(size 0.4318 0.4318)
			(layers "F.Cu" "F.Mask" "F.Paste")
			(net "GND")
		)
		(pad "BK73" smd circle
			(at 22.77491 -3.939286 270)
			(size 0.4318 0.4318)
			(layers "F.Cu" "F.Mask" "F.Paste")
			(net "UPI_CPU0_CPU1_P2P2_DN<22>")
		)
		(pad "BK75" smd circle
			(at 24.402796 -3.939286 270)
			(size 0.4318 0.4318)
			(layers "F.Cu" "F.Mask" "F.Paste")
			(net "GND")
		)
		(pad "BK77" smd circle
			(at 26.030682 -3.939286 270)
			(size 0.4318 0.4318)
			(layers "F.Cu" "F.Mask" "F.Paste")
			(net "UPI_CPU0_CPU1_P2P2_DP<18>")
		)
		(pad "BK79" smd circle
			(at 27.658314 -3.939286 270)
			(size 0.4318 0.4318)
			(layers "F.Cu" "F.Mask" "F.Paste")
			(net "GND")
		)
		(pad "BK81" smd circle
			(at 29.2862 -3.939286 270)
			(size 0.4318 0.4318)
			(layers "F.Cu" "F.Mask" "F.Paste")
			(net "PVCCIN_CPU1")
		)
		(pad "BK83" smd circle
			(at 30.914086 -3.939286 270)
			(size 0.4318 0.4318)
			(layers "F.Cu" "F.Mask" "F.Paste")
			(net "PVCCIN_CPU1")
		)
		(pad "BK85" smd circle
			(at 32.541718 -3.939286 270)
			(size 0.4318 0.4318)
			(layers "F.Cu" "F.Mask" "F.Paste")
			(net "PVCCIN_CPU1")
		)
		(pad "BK87" smd circle
			(at 34.169604 -3.939286 270)
			(size 0.4318 0.4318)
			(layers "F.Cu" "F.Mask" "F.Paste")
			(net "PVCCIN_CPU1")
		)
		(pad "BK89" smd circle
			(at 35.797236 -3.939286 270)
			(size 0.4318 0.4318)
			(layers "F.Cu" "F.Mask" "F.Paste")
			(net "PVCCIN_CPU1")
		)
		(pad "BK91" smd oval
			(at 37.425122 -3.939286)
			(size 0.381 0.4826)
			(drill
				(offset 0 -0.0508)
			)
			(layers "F.Cu" "F.Mask" "F.Paste")
			(net "PVCCIN_CPU1")
		)
		(pad "BL1" smd oval
			(at -37.425122 -3.579114 180)
			(size 0.381 0.4826)
			(drill
				(offset 0 -0.0508)
			)
			(layers "F.Cu" "F.Mask" "F.Paste")
			(net "GND")
		)
		(pad "BL3" smd circle
			(at -35.797236 -3.579114 270)
			(size 0.4318 0.4318)
			(layers "F.Cu" "F.Mask" "F.Paste")
			(net "UPI_CPU1_CPU0_P0P1_DP<21>")
		)
		(pad "BL5" smd circle
			(at -34.169604 -3.579114 270)
			(size 0.4318 0.4318)
			(layers "F.Cu" "F.Mask" "F.Paste")
			(net "GND")
		)
		(pad "BL7" smd circle
			(at -32.541718 -3.579114 270)
			(size 0.4318 0.4318)
			(layers "F.Cu" "F.Mask" "F.Paste")
			(net "UPI_CPU0_CPU1_P1P0_DP<20>")
		)
		(pad "BL9" smd circle
			(at -30.914086 -3.579114 270)
			(size 0.4318 0.4318)
			(layers "F.Cu" "F.Mask" "F.Paste")
			(net "GND")
		)
		(pad "BL11" smd circle
			(at -29.2862 -3.579114 270)
			(size 0.4318 0.4318)
			(layers "F.Cu" "F.Mask" "F.Paste")
			(net "P5E_CPU1_PE1_RX_DN<11>")
		)
		(pad "BL13" smd circle
			(at -27.658314 -3.579114 270)
			(size 0.4318 0.4318)
			(layers "F.Cu" "F.Mask" "F.Paste")
			(net "GND")
		)
		(pad "BL15" smd circle
			(at -26.030682 -3.579114 270)
			(size 0.4318 0.4318)
			(layers "F.Cu" "F.Mask" "F.Paste")
			(net "P5E_CPU1_PE1_TX_DP<12>")
		)
		(pad "BL17" smd circle
			(at -24.402796 -3.579114 270)
			(size 0.4318 0.4318)
			(layers "F.Cu" "F.Mask" "F.Paste")
			(net "GND")
		)
		(pad "BL19" smd circle
			(at -22.77491 -3.579114 270)
			(size 0.4318 0.4318)
			(layers "F.Cu" "F.Mask" "F.Paste")
			(net "TP_DMI_CPU1_PCH_RX_C_DP<4>")
		)
		(pad "BL21" smd circle
			(at -21.147278 -3.579114 270)
			(size 0.4318 0.4318)
			(layers "F.Cu" "F.Mask" "F.Paste")
			(net "NC_CPU1_PE0_APROBE<1>")
		)
		(pad "BL23" smd circle
			(at -19.519392 -3.579114 270)
			(size 0.4318 0.4318)
			(layers "F.Cu" "F.Mask" "F.Paste")
			(net "DBP_CPU1_MBP0_GTL_R_N")
		)
		(pad "BL25" smd circle
			(at -17.89176 -3.579114 270)
			(size 0.4318 0.4318)
			(layers "F.Cu" "F.Mask" "F.Paste")
			(net "SVID_DIO1_CPU1")
		)
		(pad "BL60" smd circle
			(at 12.19454 -3.469132 270)
			(size 0.4318 0.4318)
			(layers "F.Cu" "F.Mask" "F.Paste")
			(net "NC_CPU1_HBM3_VIEWDIG1")
		)
		(pad "BL62" smd circle
			(at 13.822426 -3.469132 270)
			(size 0.4318 0.4318)
			(layers "F.Cu" "F.Mask" "F.Paste")
			(net "H_CPU1_THERMTRIP_LVC1_R_N")
		)
		(pad "BL64" smd circle
			(at 15.450058 -3.469132 270)
			(size 0.4318 0.4318)
			(layers "F.Cu" "F.Mask" "F.Paste")
			(net "FM_CPU1_PKGID0")
		)
		(pad "BL66" smd circle
			(at 17.07769 -3.469132 270)
			(size 0.4318 0.4318)
			(layers "F.Cu" "F.Mask" "F.Paste")
			(net "TP_TRC_CPU1_PTI<29>")
		)
		(pad "BL68" smd circle
			(at 18.705576 -3.469132 270)
			(size 0.4318 0.4318)
			(layers "F.Cu" "F.Mask" "F.Paste")
			(net "GND")
		)
		(pad "BL70" smd circle
			(at 20.333462 -3.469132 270)
			(size 0.4318 0.4318)
			(layers "F.Cu" "F.Mask" "F.Paste")
			(net "GND")
		)
		(pad "BL72" smd circle
			(at 21.961094 -3.469132 270)
			(size 0.4318 0.4318)
			(layers "F.Cu" "F.Mask" "F.Paste")
			(net "GND")
		)
		(pad "BL74" smd circle
			(at 23.58898 -3.469132 270)
			(size 0.4318 0.4318)
			(layers "F.Cu" "F.Mask" "F.Paste")
			(net "UPI_CPU0_CPU1_P2P2_DP<22>")
		)
		(pad "BL76" smd circle
			(at 25.216612 -3.469132 270)
			(size 0.4318 0.4318)
			(layers "F.Cu" "F.Mask" "F.Paste")
			(net "UPI_CPU0_CPU1_P2P2_DN<19>")
		)
		(pad "BL78" smd circle
			(at 26.844498 -3.469132 270)
			(size 0.4318 0.4318)
			(layers "F.Cu" "F.Mask" "F.Paste")
			(net "GND")
		)
		(pad "BL80" smd circle
			(at 28.472384 -3.469132 270)
			(size 0.4318 0.4318)
			(layers "F.Cu" "F.Mask" "F.Paste")
			(net "PVCCIN_CPU1")
		)
		(pad "BL82" smd circle
			(at 30.100016 -3.469132 270)
			(size 0.4318 0.4318)
			(layers "F.Cu" "F.Mask" "F.Paste")
			(net "PVCCIN_CPU1")
		)
		(pad "BL84" smd circle
			(at 31.727902 -3.469132 270)
			(size 0.4318 0.4318)
			(layers "F.Cu" "F.Mask" "F.Paste")
			(net "PVCCIN_CPU1")
		)
		(pad "BL86" smd circle
			(at 33.355534 -3.469132 270)
			(size 0.4318 0.4318)
			(layers "F.Cu" "F.Mask" "F.Paste")
			(net "PVCCIN_CPU1")
		)
		(pad "BL88" smd circle
			(at 34.98342 -3.469132 270)
			(size 0.4318 0.4318)
			(layers "F.Cu" "F.Mask" "F.Paste")
			(net "PVCCIN_CPU1")
		)
		(pad "BL90" smd circle
			(at 36.611306 -3.469132 270)
			(size 0.4318 0.4318)
			(layers "F.Cu" "F.Mask" "F.Paste")
			(net "PVCCIN_CPU1")
		)
		(pad "BM2" smd oval
			(at -36.611306 -3.109468 180)
			(size 0.381 0.4826)
			(drill
				(offset 0 -0.0508)
			)
			(layers "F.Cu" "F.Mask" "F.Paste")
			(net "UPI_CPU1_CPU0_P0P1_DN<21>")
		)
		(pad "BM4" smd circle
			(at -34.98342 -3.109468 270)
			(size 0.4318 0.4318)
			(layers "F.Cu" "F.Mask" "F.Paste")
			(net "GND")
		)
		(pad "BM6" smd circle
			(at -33.355534 -3.109468 270)
			(size 0.4318 0.4318)
			(layers "F.Cu" "F.Mask" "F.Paste")
			(net "UPI_CPU0_CPU1_P1P0_DP<21>")
		)
		(pad "BM8" smd circle
			(at -31.727902 -3.109468 270)
			(size 0.4318 0.4318)
			(layers "F.Cu" "F.Mask" "F.Paste")
			(net "GND")
		)
		(pad "BM10" smd circle
			(at -30.100016 -3.109468 270)
			(size 0.4318 0.4318)
			(layers "F.Cu" "F.Mask" "F.Paste")
			(net "P5E_CPU1_PE1_RX_DP<11>")
		)
		(pad "BM12" smd circle
			(at -28.472384 -3.109468 270)
			(size 0.4318 0.4318)
			(layers "F.Cu" "F.Mask" "F.Paste")
			(net "GND")
		)
		(pad "BM14" smd circle
			(at -26.844498 -3.109468 270)
			(size 0.4318 0.4318)
			(layers "F.Cu" "F.Mask" "F.Paste")
			(net "P5E_CPU1_PE1_TX_DP<11>")
		)
		(pad "BM16" smd circle
			(at -25.216612 -3.109468 270)
			(size 0.4318 0.4318)
			(layers "F.Cu" "F.Mask" "F.Paste")
			(net "GND")
		)
		(pad "BM18" smd circle
			(at -23.58898 -3.109468 270)
			(size 0.4318 0.4318)
			(layers "F.Cu" "F.Mask" "F.Paste")
			(net "TP_DMI_CPU1_PCH_RX_C_DP<5>")
		)
		(pad "BM20" smd circle
			(at -21.961094 -3.109468 270)
			(size 0.4318 0.4318)
			(layers "F.Cu" "F.Mask" "F.Paste")
			(net "GND")
		)
		(pad "BM22" smd circle
			(at -20.333462 -3.109468 270)
			(size 0.4318 0.4318)
			(layers "F.Cu" "F.Mask" "F.Paste")
			(net "GND")
		)
		(pad "BM24" smd circle
			(at -18.705576 -3.109468 270)
			(size 0.4318 0.4318)
			(layers "F.Cu" "F.Mask" "F.Paste")
			(net "GND")
		)
		(pad "BM26" smd circle
			(at -17.07769 -3.109468 270)
			(size 0.4318 0.4318)
			(layers "F.Cu" "F.Mask" "F.Paste")
			(net "GND")
		)
		(pad "BM61" smd circle
			(at 13.008356 -2.999486 270)
			(size 0.4318 0.4318)
			(layers "F.Cu" "F.Mask" "F.Paste")
			(net "GND")
		)
		(pad "BM63" smd circle
			(at 14.635988 -2.999486 270)
			(size 0.4318 0.4318)
			(layers "F.Cu" "F.Mask" "F.Paste")
			(net "NC_ESPI_IBL_CPU1_IO3")
		)
		(pad "BM65" smd circle
			(at 16.263874 -2.999486 270)
			(size 0.4318 0.4318)
			(layers "F.Cu" "F.Mask" "F.Paste")
			(net "NC_CPU1_SOC_SPARE1")
		)
		(pad "BM67" smd circle
			(at 17.89176 -2.999486 270)
			(size 0.4318 0.4318)
			(layers "F.Cu" "F.Mask" "F.Paste")
			(net "TP_TRC_CPU1_PTI<30>")
		)
		(pad "BM69" smd circle
			(at 19.519392 -2.999486 270)
			(size 0.4318 0.4318)
			(layers "F.Cu" "F.Mask" "F.Paste")
			(net "TP_TRC_CPU1_PTI<25>")
		)
		(pad "BM71" smd circle
			(at 21.147278 -2.999486 270)
			(size 0.4318 0.4318)
			(layers "F.Cu" "F.Mask" "F.Paste")
			(net "UPI_CPU1_CPU0_P2P2_DN<23>")
		)
		(pad "BM73" smd circle
			(at 22.77491 -2.999486 270)
			(size 0.4318 0.4318)
			(layers "F.Cu" "F.Mask" "F.Paste")
			(net "GND")
		)
		(pad "BM75" smd circle
			(at 24.402796 -2.999486 270)
			(size 0.4318 0.4318)
			(layers "F.Cu" "F.Mask" "F.Paste")
			(net "UPI_CPU0_CPU1_P2P2_DP<21>")
		)
	)
)
